# S9S_MB_2U (Grand Teton) — schematic netlist excerpt (pin names and nets, part order shuffled) for the footprints in the layout excerpt that follows; sources: Cadence DE-HDL packaged netlist, KiCad conversion of 03242023_DA0F0TMBIJ0_F0T_Motherboard_J_brd_V01_OCP.brd

PC2367  Q_CAP  0.1UF 25V 10% EMPTY  pkg 0402  page 292 : A = PVCCINFAON_CPU1_VCC ; B = GND
R4757  Q_RES  0 5% EMPTY  pkg 0402LF  page 164 : A = HP_LVC3_OCP_V3_2_PWRGD_R2 ; B = OCP_V3_2_AUX_PWR_EN_R2

(kicad_pcb
	(version 20260206)
	(generator "pcbnew")
	(generator_version "10.0")
	(general
		(thickness 1.6)
		(legacy_teardrops no)
	)
	(paper "A4")
	(title_block
		(title "03242023_DA0F0TMBIJ0_F0T_Motherboard_J_brd_V01_OCP.brd")
		(comment 1 "Grand Teton / footprints 1525-1526 of 6105")
	)
	(layers
		(0 "F.Cu" signal "TOP")
		(4 "In1.Cu" signal "GND")
		(6 "In2.Cu" signal "IN1")
		(8 "In3.Cu" signal "GND1")
		(10 "In4.Cu" signal "IN2")
		(12 "In5.Cu" signal "GND2")
		(14 "In6.Cu" signal "IN3")
		(16 "In7.Cu" signal "GND3")
		(18 "In8.Cu" signal "VCC")
		(20 "In9.Cu" signal "VCC1")
		(22 "In10.Cu" signal "GND4")
		(24 "In11.Cu" signal "IN4")
		(26 "In12.Cu" signal "GND5")
		(28 "In13.Cu" signal "IN5")
		(30 "In14.Cu" signal "GND6")
		(32 "In15.Cu" signal "IN6")
		(34 "In16.Cu" signal "GND7")
		(2 "B.Cu" signal "BOTTOM")
		(9 "F.Adhes" user "F.Adhesive")
		(11 "B.Adhes" user "B.Adhesive")
		(13 "F.Paste" user "Package Geometry/Pastemask Top")
		(15 "B.Paste" user "Package Geometry/Pastemask Bottom")
		(5 "F.SilkS" user "Ref Des/Silkscreen Top")
		(7 "B.SilkS" user "Ref Des/Silkscreen Bottom")
		(1 "F.Mask" user "Board Geometry/Soldermask Top")
		(3 "B.Mask" user "Board Geometry/Soldermask Bottom")
		(17 "Dwgs.User" user "User.Drawings")
		(19 "Cmts.User" user "User.Comments")
		(21 "Eco1.User" user "User.Eco1")
		(23 "Eco2.User" user "User.Eco2")
		(25 "Edge.Cuts" user "Board Geometry/Outline")
		(27 "Margin" user)
		(31 "F.CrtYd" user "Package Geometry/Place Bound Top")
		(29 "B.CrtYd" user "Package Geometry/Place Bound Bottom")
		(35 "F.Fab" user "Ref Des/Assembly Top")
		(33 "B.Fab" user "Ref Des/Assembly Bottom")
	)
	(footprint ""
		(layer "F.Cu")
		(at 27.03068 -125.368812 180)
		(property "Reference" "PC2367"
			(at 0 0 180)
			(layer "F.SilkS")
			(hide yes)
			(effects
				(font
					(size 1.27 1.27)
				)
			)
		)
		(property "Value" ""
			(at 0 0 180)
			(layer "F.Fab")
			(effects
				(font
					(size 1.27 1.27)
				)
			)
		)
		(duplicate_pad_numbers_are_jumpers no)
		(fp_line
			(start 0.7874 0.4064)
			(end -0.7874 0.4064)
			(stroke
				(width 0.1524)
				(type default)
			)
			(layer "F.SilkS")
		)
		(fp_line
			(start 0.7874 -0.4064)
			(end 0.7874 0.4064)
			(stroke
				(width 0.1524)
				(type default)
			)
			(layer "F.SilkS")
		)
		(fp_line
			(start -0.7874 0.4064)
			(end -0.7874 -0.4064)
			(stroke
				(width 0.1524)
				(type default)
			)
			(layer "F.SilkS")
		)
		(fp_line
			(start -0.7874 -0.4064)
			(end 0.7874 -0.4064)
			(stroke
				(width 0.1524)
				(type default)
			)
			(layer "F.SilkS")
		)
		(fp_line
			(start 0.67945 0.3048)
			(end 0.120396 0.3048)
			(stroke
				(width 0.1)
				(type default)
			)
			(layer "F.Fab")
		)
		(fp_line
			(start 0.67945 -0.3048)
			(end 0.67945 0.3048)
			(stroke
				(width 0.1)
				(type default)
			)
			(layer "F.Fab")
		)
		(fp_line
			(start 0.12065 -0.2794)
			(end 0.12065 -0.3048)
			(stroke
				(width 0.1)
				(type default)
			)
			(layer "F.Fab")
		)
		(fp_line
			(start 0.12065 -0.3048)
			(end 0.67945 -0.3048)
			(stroke
				(width 0.1)
				(type default)
			)
			(layer "F.Fab")
		)
		(fp_line
			(start 0.120396 0.3048)
			(end 0.120396 0.2794)
			(stroke
				(width 0.1)
				(type default)
			)
			(layer "F.Fab")
		)
		(fp_line
			(start 0.120396 0.2794)
			(end -0.12065 0.2794)
			(stroke
				(width 0.1)
				(type default)
			)
			(layer "F.Fab")
		)
		(fp_line
			(start -0.12065 0.3048)
			(end -0.67945 0.3048)
			(stroke
				(width 0.1)
				(type default)
			)
			(layer "F.Fab")
		)
		(fp_line
			(start -0.12065 0.2794)
			(end -0.12065 0.3048)
			(stroke
				(width 0.1)
				(type default)
			)
			(layer "F.Fab")
		)
		(fp_line
			(start -0.12065 -0.2794)
			(end 0.12065 -0.2794)
			(stroke
				(width 0.1)
				(type default)
			)
			(layer "F.Fab")
		)
		(fp_line
			(start -0.12065 -0.305054)
			(end -0.12065 -0.2794)
			(stroke
				(width 0.1)
				(type default)
			)
			(layer "F.Fab")
		)
		(fp_line
			(start -0.67945 0.3048)
			(end -0.67945 -0.305054)
			(stroke
				(width 0.1)
				(type default)
			)
			(layer "F.Fab")
		)
		(fp_line
			(start -0.67945 -0.305054)
			(end -0.12065 -0.305054)
			(stroke
				(width 0.1)
				(type default)
			)
			(layer "F.Fab")
		)
		(pad "1" smd circle
			(at -0.40005 0 180)
			(size 0 0)
			(layers "F.Cu" "F.Mask" "F.Paste")
			(net "PVCCINFAON_CPU1_VCC")
		)
		(pad "2" smd circle
			(at 0.40005 0 180)
			(size 0 0)
			(layers "F.Cu" "F.Mask" "F.Paste")
			(net "GND")
		)
	)
	(footprint ""
		(layer "F.Cu")
		(at 136.3853 -115.38458 180)
		(property "Reference" "R4757"
			(at 0 0 180)
			(layer "F.SilkS")
			(hide yes)
			(effects
				(font
					(size 1.27 1.27)
				)
			)
		)
		(property "Value" ""
			(at 0 0 180)
			(layer "F.Fab")
			(effects
				(font
					(size 1.27 1.27)
				)
			)
		)
		(duplicate_pad_numbers_are_jumpers no)
		(fp_line
			(start 0.7874 0.4064)
			(end -0.7874 0.4064)
			(stroke
				(width 0.1524)
				(type default)
			)
			(layer "F.SilkS")
		)
		(fp_line
			(start 0.7874 -0.4064)
			(end 0.7874 0.4064)
			(stroke
				(width 0.1524)
				(type default)
			)
			(layer "F.SilkS")
		)
		(fp_line
			(start -0.7874 0.4064)
			(end -0.7874 -0.4064)
			(stroke
				(width 0.1524)
				(type default)
			)
			(layer "F.SilkS")
		)
		(fp_line
			(start -0.7874 -0.4064)
			(end 0.7874 -0.4064)
			(stroke
				(width 0.1524)
				(type default)
			)
			(layer "F.SilkS")
		)
		(fp_line
			(start 0.67945 0.3048)
			(end 0.120396 0.3048)
			(stroke
				(width 0.1)
				(type default)
			)
			(layer "F.Fab")
		)
		(fp_line
			(start 0.67945 -0.3048)
			(end 0.67945 0.3048)
			(stroke
				(width 0.1)
				(type default)
			)
			(layer "F.Fab")
		)
		(fp_line
			(start 0.12065 -0.2794)
			(end 0.12065 -0.3048)
			(stroke
				(width 0.1)
				(type default)
			)
			(layer "F.Fab")
		)
		(fp_line
			(start 0.12065 -0.3048)
			(end 0.67945 -0.3048)
			(stroke
				(width 0.1)
				(type default)
			)
			(layer "F.Fab")
		)
		(fp_line
			(start 0.120396 0.3048)
			(end 0.120396 0.2794)
			(stroke
				(width 0.1)
				(type default)
			)
			(layer "F.Fab")
		)
		(fp_line
			(start 0.120396 0.2794)
			(end -0.12065 0.2794)
			(stroke
				(width 0.1)
				(type default)
			)
			(layer "F.Fab")
		)
		(fp_line
			(start -0.12065 0.3048)
			(end -0.67945 0.3048)
			(stroke
				(width 0.1)
				(type default)
			)
			(layer "F.Fab")
		)
		(fp_line
			(start -0.12065 0.2794)
			(end -0.12065 0.3048)
			(stroke
				(width 0.1)
				(type default)
			)
			(layer "F.Fab")
		)
		(fp_line
			(start -0.12065 -0.2794)
			(end 0.12065 -0.2794)
			(stroke
				(width 0.1)
				(type default)
			)
			(layer "F.Fab")
		)
		(fp_line
			(start -0.12065 -0.305054)
			(end -0.12065 -0.2794)
			(stroke
				(width 0.1)
				(type default)
			)
			(layer "F.Fab")
		)
		(fp_line
			(start -0.67945 0.3048)
			(end -0.67945 -0.305054)
			(stroke
				(width 0.1)
				(type default)
			)
			(layer "F.Fab")
		)
		(fp_line
			(start -0.67945 -0.305054)
			(end -0.12065 -0.305054)
			(stroke
				(width 0.1)
				(type default)
			)
			(layer "F.Fab")
		)
		(pad "1" smd circle
			(at -0.40005 0 180)
			(size 0 0)
			(layers "F.Cu" "F.Mask" "F.Paste")
			(net "HP_LVC3_OCP_V3_2_PWRGD_R2")
		)
		(pad "2" smd circle
			(at 0.40005 0 180)
			(size 0 0)
			(layers "F.Cu" "F.Mask" "F.Paste")
			(net "OCP_V3_2_AUX_PWR_EN_R2")
		)
	)
)
